(kicad_pcb
	(version 20260206)
	(generator "pcbnew")
	(generator_version "10.0")
	(general
		(thickness 1.6)
		(legacy_teardrops no)
	)
	(paper "A4")
	(title_block
		(title "fcb — 12433-1M.1206WZS1330.brd")
		(comment 1 "Open Vault / Knox (Wiwynn) / footprints 106-109 of 495")
	)
	(layers
		(0 "F.Cu" signal "TOP")
		(4 "In1.Cu" signal "L2GND")
		(6 "In2.Cu" signal "L3VCC")
		(2 "B.Cu" signal "BOTTOM")
		(9 "F.Adhes" user "F.Adhesive")
		(11 "B.Adhes" user "B.Adhesive")
		(13 "F.Paste" user "Package Geometry/Pastemask Top")
		(15 "B.Paste" user "Package Geometry/Pastemask Bottom")
		(5 "F.SilkS" user "Ref Des/Silkscreen Top")
		(7 "B.SilkS" user "Ref Des/Silkscreen Bottom")
		(1 "F.Mask" user "Board Geometry/Soldermask Top")
		(3 "B.Mask" user "Board Geometry/Soldermask Bottom")
		(17 "Dwgs.User" user "User.Drawings")
		(19 "Cmts.User" user "User.Comments")
		(21 "Eco1.User" user "User.Eco1")
		(23 "Eco2.User" user "User.Eco2")
		(25 "Edge.Cuts" user "Board Geometry/Outline")
		(27 "Margin" user)
		(31 "F.CrtYd" user "Package Geometry/Place Bound Top")
		(29 "B.CrtYd" user "Package Geometry/Place Bound Bottom")
		(35 "F.Fab" user "Ref Des/Assembly Top")
		(33 "B.Fab" user "Ref Des/Assembly Bottom")
	)
	(footprint ""
		(layer "F.Cu")
		(at 22.479508 -286.917638)
		(property "Reference" "D10"
			(at 0 0 0)
			(layer "F.SilkS")
			(hide yes)
			(effects
				(font
					(size 1.27 1.27)
				)
			)
		)
		(property "Value" "BAS16H-GP"
			(at 0 -5.5372 0)
			(unlocked yes)
			(layer "F.Fab")
			(hide yes)
			(effects
				(font
					(size 1.016 1.016)
					(thickness 0.1524)
				)
			)
		)
		(property "Device Type" "SOD123AKH48"
			(at 0 -7.0612 0)
			(unlocked yes)
			(layer "F.Fab")
			(hide yes)
			(effects
				(font
					(size 1.016 1.016)
					(thickness 0.1524)
				)
			)
		)
		(duplicate_pad_numbers_are_jumpers no)
		(fp_line
			(start -1.016 -2.667)
			(end -1.016 2.667)
			(stroke
				(width 0.1524)
				(type default)
			)
			(layer "F.SilkS")
		)
		(fp_line
			(start -1.016 2.667)
			(end 1.016 2.667)
			(stroke
				(width 0.1524)
				(type default)
			)
			(layer "F.SilkS")
		)
		(fp_line
			(start 0.889 2.921)
			(end -0.889 2.921)
			(stroke
				(width 0.508)
				(type default)
			)
			(layer "F.SilkS")
		)
		(fp_line
			(start 1.016 -2.667)
			(end -1.016 -2.667)
			(stroke
				(width 0.1524)
				(type default)
			)
			(layer "F.SilkS")
		)
		(fp_line
			(start 1.016 2.667)
			(end 1.016 -2.667)
			(stroke
				(width 0.1524)
				(type default)
			)
			(layer "F.SilkS")
		)
		(fp_rect
			(start -1.143 3.175)
			(end 1.143 -2.794)
			(stroke
				(width 0)
				(type default)
			)
			(fill no)
			(layer "F.CrtYd")
		)
		(fp_poly
			(pts
				(xy -1.143 -2.794) (xy 1.143 -2.794) (xy 1.143 3.175) (xy -1.143 3.175)
			)
			(stroke
				(width 0)
				(type default)
			)
			(fill no)
			(layer "F.Fab")
		)
		(pad "A" smd rect
			(at 0 -1.6891)
			(size 0.889 1.397)
			(layers "F.Cu" "F.Mask" "F.Paste")
			(net "FAN_TACH4")
		)
		(pad "K" smd rect
			(at 0 1.6891)
			(size 0.889 1.397)
			(layers "F.Cu" "F.Mask" "F.Paste")
			(net "P12V")
		)
	)
	(footprint ""
		(layer "F.Cu")
		(at 38.5826 -356.921816)
		(property "Reference" "PQ14"
			(at 0 0 0)
			(layer "F.SilkS")
			(hide yes)
			(effects
				(font
					(size 1.27 1.27)
				)
			)
		)
		(property "Value" "PMBS3904-1-GP"
			(at 0 -9.0932 0)
			(unlocked yes)
			(layer "F.Fab")
			(hide yes)
			(effects
				(font
					(size 1.016 1.016)
					(thickness 0.1524)
				)
			)
		)
		(property "Device Type" "SOT-23-10H44"
			(at 0 -10.6172 0)
			(unlocked yes)
			(layer "F.Fab")
			(hide yes)
			(effects
				(font
					(size 1.016 1.016)
					(thickness 0.1524)
				)
			)
		)
		(duplicate_pad_numbers_are_jumpers no)
		(fp_line
			(start -1.7526 1.8796)
			(end -1.7526 0.9906)
			(stroke
				(width 0.3302)
				(type default)
			)
			(layer "F.SilkS")
		)
		(fp_line
			(start -1.651 -1.778)
			(end -1.651 1.778)
			(stroke
				(width 0.1524)
				(type default)
			)
			(layer "F.SilkS")
		)
		(fp_line
			(start -1.651 1.778)
			(end 1.651 1.778)
			(stroke
				(width 0.1524)
				(type default)
			)
			(layer "F.SilkS")
		)
		(fp_line
			(start -1.279398 2.152142)
			(end -0.9906 1.86309)
			(stroke
				(width 0.0127)
				(type default)
			)
			(layer "F.SilkS")
		)
		(fp_line
			(start -1.279144 2.15265)
			(end -0.701294 2.15265)
			(stroke
				(width 0.0127)
				(type default)
			)
			(layer "F.SilkS")
		)
		(fp_line
			(start -1.260856 2.1336)
			(end -0.720344 2.1336)
			(stroke
				(width 0.0127)
				(type default)
			)
			(layer "F.SilkS")
		)
		(fp_line
			(start -1.251458 2.124202)
			(end -0.729996 2.124202)
			(stroke
				(width 0.0127)
				(type default)
			)
			(layer "F.SilkS")
		)
		(fp_line
			(start -1.241806 2.11455)
			(end -0.739394 2.11455)
			(stroke
				(width 0.0127)
				(type default)
			)
			(layer "F.SilkS")
		)
		(fp_line
			(start -1.232408 2.105152)
			(end -0.749046 2.105152)
			(stroke
				(width 0.0127)
				(type default)
			)
			(layer "F.SilkS")
		)
		(fp_line
			(start -1.222756 2.0955)
			(end -0.758444 2.0955)
			(stroke
				(width 0.0127)
				(type default)
			)
			(layer "F.SilkS")
		)
		(fp_line
			(start -1.213358 2.086102)
			(end -0.768096 2.086102)
			(stroke
				(width 0.0127)
				(type default)
			)
			(layer "F.SilkS")
		)
		(fp_line
			(start -1.203706 2.07645)
			(end -0.777494 2.07645)
			(stroke
				(width 0.0127)
				(type default)
			)
			(layer "F.SilkS")
		)
		(fp_line
			(start -1.194308 2.067052)
			(end -0.787146 2.067052)
			(stroke
				(width 0.0127)
				(type default)
			)
			(layer "F.SilkS")
		)
		(fp_line
			(start -1.184656 2.0574)
			(end -0.796544 2.0574)
			(stroke
				(width 0.0127)
				(type default)
			)
			(layer "F.SilkS")
		)
		(fp_line
			(start -1.175258 2.048002)
			(end -0.806196 2.048002)
			(stroke
				(width 0.0127)
				(type default)
			)
			(layer "F.SilkS")
		)
		(fp_line
			(start -1.165606 2.03835)
			(end -0.815594 2.03835)
			(stroke
				(width 0.0127)
				(type default)
			)
			(layer "F.SilkS")
		)
		(fp_line
			(start -1.156208 2.028952)
			(end -0.825246 2.028952)
			(stroke
				(width 0.0127)
				(type default)
			)
			(layer "F.SilkS")
		)
		(fp_line
			(start -1.146556 2.0193)
			(end -0.834644 2.0193)
			(stroke
				(width 0.0127)
				(type default)
			)
			(layer "F.SilkS")
		)
		(fp_line
			(start -1.137158 2.009902)
			(end -0.844296 2.009902)
			(stroke
				(width 0.0127)
				(type default)
			)
			(layer "F.SilkS")
		)
		(fp_line
			(start -1.127506 2.00025)
			(end -0.853694 2.00025)
			(stroke
				(width 0.0127)
				(type default)
			)
			(layer "F.SilkS")
		)
		(fp_line
			(start -1.118108 1.990852)
			(end -0.863346 1.990852)
			(stroke
				(width 0.0127)
				(type default)
			)
			(layer "F.SilkS")
		)
		(fp_line
			(start -1.108456 1.9812)
			(end -0.872744 1.9812)
			(stroke
				(width 0.0127)
				(type default)
			)
			(layer "F.SilkS")
		)
		(fp_line
			(start -1.099058 1.971802)
			(end -0.882396 1.971802)
			(stroke
				(width 0.0127)
				(type default)
			)
			(layer "F.SilkS")
		)
		(fp_line
			(start -1.089406 1.96215)
			(end -0.891794 1.96215)
			(stroke
				(width 0.0127)
				(type default)
			)
			(layer "F.SilkS")
		)
		(fp_line
			(start -1.080008 1.952752)
			(end -0.901446 1.952752)
			(stroke
				(width 0.0127)
				(type default)
			)
			(layer "F.SilkS")
		)
		(fp_line
			(start -1.070356 1.9431)
			(end -0.910844 1.9431)
			(stroke
				(width 0.0127)
				(type default)
			)
			(layer "F.SilkS")
		)
		(fp_line
			(start -1.060958 1.933702)
			(end -0.920496 1.933702)
			(stroke
				(width 0.0127)
				(type default)
			)
			(layer "F.SilkS")
		)
		(fp_line
			(start -1.051306 1.92405)
			(end -0.929894 1.92405)
			(stroke
				(width 0.0127)
				(type default)
			)
			(layer "F.SilkS")
		)
		(fp_line
			(start -1.041908 1.914652)
			(end -0.939546 1.914652)
			(stroke
				(width 0.0127)
				(type default)
			)
			(layer "F.SilkS")
		)
		(fp_line
			(start -1.032256 1.905)
			(end -0.948944 1.905)
			(stroke
				(width 0.0127)
				(type default)
			)
			(layer "F.SilkS")
		)
		(fp_line
			(start -1.022858 1.895602)
			(end -0.958596 1.895602)
			(stroke
				(width 0.0127)
				(type default)
			)
			(layer "F.SilkS")
		)
		(fp_line
			(start -1.013206 1.88595)
			(end -0.967994 1.88595)
			(stroke
				(width 0.0127)
				(type default)
			)
			(layer "F.SilkS")
		)
		(fp_line
			(start -1.003808 1.876552)
			(end -0.977646 1.876552)
			(stroke
				(width 0.0127)
				(type default)
			)
			(layer "F.SilkS")
		)
		(fp_line
			(start -0.994156 1.8669)
			(end -0.987044 1.8669)
			(stroke
				(width 0.0127)
				(type default)
			)
			(layer "F.SilkS")
		)
		(fp_line
			(start -0.9906 1.86309)
			(end -0.701294 2.15265)
			(stroke
				(width 0.0127)
				(type default)
			)
			(layer "F.SilkS")
		)
		(fp_line
			(start -0.719074 2.145538)
			(end -1.265936 2.14122)
			(stroke
				(width 0.0127)
				(type default)
			)
			(layer "F.SilkS")
		)
		(fp_line
			(start -0.71628 2.15265)
			(end -1.26492 2.15265)
			(stroke
				(width 0.0127)
				(type default)
			)
			(layer "F.SilkS")
		)
		(fp_line
			(start -0.635 1.8796)
			(end -1.7526 1.8796)
			(stroke
				(width 0.3302)
				(type default)
			)
			(layer "F.SilkS")
		)
		(fp_line
			(start 1.651 -1.778)
			(end -1.651 -1.778)
			(stroke
				(width 0.1524)
				(type default)
			)
			(layer "F.SilkS")
		)
		(fp_line
			(start 1.651 1.778)
			(end 1.651 -1.778)
			(stroke
				(width 0.1524)
				(type default)
			)
			(layer "F.SilkS")
		)
		(fp_poly
			(pts
				(xy -1.285748 2.159) (xy -1.285748 1.8796) (xy -1.778 1.8796) (xy -1.778 -1.8796) (xy 1.778 -1.8796)
				(xy 1.778 1.8796) (xy -0.694944 1.8796) (xy -0.694944 2.159)
			)
			(stroke
				(width 0)
				(type default)
			)
			(fill no)
			(layer "F.CrtYd")
		)
		(fp_poly
			(pts
				(xy -1.285748 2.159) (xy -1.285748 1.8796) (xy -1.778 1.8796) (xy -1.778 -1.8796) (xy 1.778 -1.8796)
				(xy 1.778 1.8796) (xy -0.694944 1.8796) (xy -0.694944 2.159)
			)
			(stroke
				(width 0)
				(type default)
			)
			(fill no)
			(layer "F.Fab")
		)
		(pad "1" smd rect
			(at -0.98425 0.9525)
			(size 0.762 1.143)
			(layers "F.Cu" "F.Mask" "F.Paste")
			(net "OTP_RETRY_B")
		)
		(pad "2" smd rect
			(at 0.98425 0.9525)
			(size 0.762 1.143)
			(layers "F.Cu" "F.Mask" "F.Paste")
			(net "GND")
		)
		(pad "3" smd rect
			(at 0 -0.9525)
			(size 0.762 1.143)
			(layers "F.Cu" "F.Mask" "F.Paste")
			(net "OTP_RETRY_C")
		)
	)
	(footprint ""
		(layer "F.Cu")
		(at 41.529 -183.185816)
		(property "Reference" "U8"
			(at 0 0 0)
			(layer "F.SilkS")
			(hide yes)
			(effects
				(font
					(size 1.27 1.27)
				)
			)
		)
		(property "Value" "TSAHC74PWR-GP"
			(at -7.112 -6.0579 0)
			(unlocked yes)
			(layer "F.Fab")
			(hide yes)
			(effects
				(font
					(size 1.016 1.016)
					(thickness 0.1524)
				)
			)
		)
		(property "Device Type" "TSOIC14H48"
			(at -7.112 -7.5819 0)
			(unlocked yes)
			(layer "F.Fab")
			(hide yes)
			(effects
				(font
					(size 1.016 1.016)
					(thickness 0.1524)
				)
			)
		)
		(duplicate_pad_numbers_are_jumpers no)
		(fp_line
			(start -2.9718 -1.778)
			(end 2.1336 -1.778)
			(stroke
				(width 0.1524)
				(type default)
			)
			(layer "F.SilkS")
		)
		(fp_line
			(start -2.9718 1.778)
			(end -2.9718 -1.778)
			(stroke
				(width 0.1524)
				(type default)
			)
			(layer "F.SilkS")
		)
		(fp_line
			(start -2.9337 -0.4699)
			(end -2.9083 -0.4699)
			(stroke
				(width 0.1524)
				(type default)
			)
			(layer "F.SilkS")
		)
		(fp_line
			(start -2.9083 -0.4699)
			(end -2.4384 0)
			(stroke
				(width 0.1524)
				(type default)
			)
			(layer "F.SilkS")
		)
		(fp_line
			(start -2.8956 0.4572)
			(end -2.921 0.4572)
			(stroke
				(width 0.1524)
				(type default)
			)
			(layer "F.SilkS")
		)
		(fp_line
			(start -2.794 3.8227)
			(end -2.794 1.7018)
			(stroke
				(width 0.508)
				(type default)
			)
			(layer "F.SilkS")
		)
		(fp_line
			(start -2.4384 0)
			(end -2.8956 0.4572)
			(stroke
				(width 0.1524)
				(type default)
			)
			(layer "F.SilkS")
		)
		(fp_line
			(start 2.1336 -1.778)
			(end 2.1336 1.778)
			(stroke
				(width 0.1524)
				(type default)
			)
			(layer "F.SilkS")
		)
		(fp_line
			(start 2.1336 1.778)
			(end -2.9718 1.778)
			(stroke
				(width 0.1524)
				(type default)
			)
			(layer "F.SilkS")
		)
		(fp_poly
			(pts
				(xy -2.1336 -1.7653) (xy 2.1336 -1.7653) (xy 2.1336 1.778) (xy -2.1336 1.778)
			)
			(stroke
				(width 0)
				(type default)
			)
			(fill yes)
			(layer "F.SilkS")
		)
		(fp_rect
			(start -2.5019 3.2004)
			(end 2.5019 -3.2004)
			(stroke
				(width 0)
				(type default)
			)
			(fill no)
			(layer "F.CrtYd")
		)
		(fp_poly
			(pts
				(xy -3.048 4.0894) (xy -3.048 -2.5781) (xy -2.5019 -2.5781) (xy -2.5019 3.2004) (xy 2.5019 3.2004)
				(xy 2.5019 -3.2004) (xy -2.5019 -3.2004) (xy -2.5019 -2.5908) (xy -3.048 -2.5908) (xy -3.048 -4.0894)
				(xy 3.048 -4.0894) (xy 3.048 4.0894)
			)
			(stroke
				(width 0)
				(type default)
			)
			(fill no)
			(layer "F.CrtYd")
		)
		(fp_rect
			(start -3.048 4.0894)
			(end 3.048 -4.0894)
			(stroke
				(width 0)
				(type default)
			)
			(fill no)
			(layer "F.Fab")
		)
		(pad "1" smd rect
			(at -1.94945 2.8194)
			(size 0.3556 1.524)
			(layers "F.Cu" "F.Mask" "F.Paste")
			(net "D_LATCH_CLR")
		)
		(pad "2" smd rect
			(at -1.30048 2.8194)
			(size 0.3556 1.524)
			(layers "F.Cu" "F.Mask" "F.Paste")
			(net "GND")
		)
		(pad "3" smd rect
			(at -0.65024 2.8194)
			(size 0.3556 1.524)
			(layers "F.Cu" "F.Mask" "F.Paste")
			(net "TEMP_ALM#_IN_D")
		)
		(pad "4" smd rect
			(at 0 2.8194)
			(size 0.3556 1.524)
			(layers "F.Cu" "F.Mask" "F.Paste")
			(net "D_LATCH_PRE#")
		)
		(pad "5" smd rect
			(at 0.65024 2.8194)
			(size 0.3556 1.524)
			(layers "F.Cu" "F.Mask" "F.Paste")
			(net "D_LATCH_Q")
		)
		(pad "6" smd rect
			(at 1.30048 2.8194)
			(size 0.3556 1.524)
			(layers "F.Cu" "F.Mask" "F.Paste")
			(net "D_LATCH_Q#")
		)
		(pad "7" smd rect
			(at 1.94945 2.8194)
			(size 0.3556 1.524)
			(layers "F.Cu" "F.Mask" "F.Paste")
			(net "GND")
		)
		(pad "8" smd rect
			(at 1.94945 -2.8194)
			(size 0.3556 1.524)
			(layers "F.Cu" "F.Mask" "F.Paste")
			(net "Net_57")
		)
		(pad "9" smd rect
			(at 1.30048 -2.8194)
			(size 0.3556 1.524)
			(layers "F.Cu" "F.Mask" "F.Paste")
			(net "Net_58")
		)
		(pad "10" smd rect
			(at 0.65024 -2.8194)
			(size 0.3556 1.524)
			(layers "F.Cu" "F.Mask" "F.Paste")
			(net "P3V3_AUX")
		)
		(pad "11" smd rect
			(at 0 -2.8194)
			(size 0.3556 1.524)
			(layers "F.Cu" "F.Mask" "F.Paste")
			(net "GND")
		)
		(pad "12" smd rect
			(at -0.65024 -2.8194)
			(size 0.3556 1.524)
			(layers "F.Cu" "F.Mask" "F.Paste")
			(net "GND")
		)
		(pad "13" smd rect
			(at -1.30048 -2.8194)
			(size 0.3556 1.524)
			(layers "F.Cu" "F.Mask" "F.Paste")
			(net "P3V3_AUX")
		)
		(pad "14" smd rect
			(at -1.94945 -2.8194)
			(size 0.3556 1.524)
			(layers "F.Cu" "F.Mask" "F.Paste")
			(net "P3V3_AUX")
		)
	)
	(footprint ""
		(layer "F.Cu")
		(at 25.654 -400.177)
		(property "Reference" "PQ1"
			(at 0 0 0)
			(layer "F.SilkS")
			(hide yes)
			(effects
				(font
					(size 1.27 1.27)
				)
			)
		)
		(property "Value" "PH0925CL-GP"
			(at -4.2799 -0.4572 0)
			(unlocked yes)
			(layer "F.Fab")
			(hide yes)
			(effects
				(font
					(size 1.016 1.016)
					(thickness 0.1524)
				)
			)
		)
		(property "Device Type" "LFPAK-5PH48-U"
			(at -4.2799 -1.9812 0)
			(unlocked yes)
			(layer "F.Fab")
			(hide yes)
			(effects
				(font
					(size 1.016 1.016)
					(thickness 0.1524)
				)
			)
		)
		(duplicate_pad_numbers_are_jumpers no)
		(fp_line
			(start -2.7559 -6.5532)
			(end -2.7559 1.0668)
			(stroke
				(width 0.1524)
				(type default)
			)
			(layer "F.SilkS")
		)
		(fp_line
			(start -2.7559 1.0668)
			(end 2.7559 1.0668)
			(stroke
				(width 0.1524)
				(type default)
			)
			(layer "F.SilkS")
		)
		(fp_line
			(start -1.7272 1.1684)
			(end -2.1082 1.1684)
			(stroke
				(width 0.3302)
				(type default)
			)
			(layer "F.SilkS")
		)
		(fp_line
			(start 2.7559 -6.5532)
			(end -2.7559 -6.5532)
			(stroke
				(width 0.1524)
				(type default)
			)
			(layer "F.SilkS")
		)
		(fp_line
			(start 2.7559 1.0668)
			(end 2.7559 -6.5532)
			(stroke
				(width 0.1524)
				(type default)
			)
			(layer "F.SilkS")
		)
		(fp_poly
			(pts
				(xy -2.3368 1.5748) (xy -1.905 1.143) (xy -1.4732 1.5748)
			)
			(stroke
				(width 0)
				(type default)
			)
			(fill yes)
			(layer "F.SilkS")
		)
		(fp_poly
			(pts
				(xy -2.5019 -4.02971) (xy -0.3302 -4.02971) (xy -0.3302 -6.30301) (xy -2.5019 -6.30301)
			)
			(stroke
				(width 0)
				(type default)
			)
			(fill yes)
			(layer "F.Paste")
		)
		(fp_poly
			(pts
				(xy -2.5019 -1.09601) (xy -0.3302 -1.09601) (xy -0.3302 -3.36931) (xy -2.5019 -3.36931)
			)
			(stroke
				(width 0)
				(type default)
			)
			(fill yes)
			(layer "F.Paste")
		)
		(fp_poly
			(pts
				(xy 0.3302 -4.02971) (xy 2.5019 -4.02971) (xy 2.5019 -6.30301) (xy 0.3302 -6.30301)
			)
			(stroke
				(width 0)
				(type default)
			)
			(fill yes)
			(layer "F.Paste")
		)
		(fp_poly
			(pts
				(xy 0.3302 -1.09601) (xy 2.5019 -1.09601) (xy 2.5019 -3.36931) (xy 0.3302 -3.36931)
			)
			(stroke
				(width 0)
				(type default)
			)
			(fill yes)
			(layer "F.Paste")
		)
		(fp_rect
			(start -2.4511 0.3048)
			(end 2.4511 -5.6896)
			(stroke
				(width 0)
				(type default)
			)
			(fill no)
			(layer "F.CrtYd")
		)
		(fp_poly
			(pts
				(xy -3.0099 1.3208) (xy -3.0099 -6.8072) (xy 3.0099 -6.8072) (xy 3.0099 -1.016) (xy 2.4511 -1.016)
				(xy 2.4511 -5.6896) (xy -2.4511 -5.6896) (xy -2.4511 0.3048) (xy 2.4511 0.3048) (xy 2.4511 -1.0033)
				(xy 3.0099 -1.0033) (xy 3.0099 1.3208)
			)
			(stroke
				(width 0)
				(type default)
			)
			(fill no)
			(layer "F.CrtYd")
		)
		(fp_rect
			(start -3.0099 1.3208)
			(end 3.0099 -6.8072)
			(stroke
				(width 0)
				(type default)
			)
			(fill no)
			(layer "F.Fab")
		)
		(pad "1" smd rect
			(at -1.905 0)
			(size 0.762 1.6256)
			(layers "F.Cu" "F.Mask" "F.Paste")
			(net "P12V")
		)
		(pad "2" smd rect
			(at -0.635 0)
			(size 0.762 1.6256)
			(layers "F.Cu" "F.Mask" "F.Paste")
			(net "P12V")
		)
		(pad "3" smd rect
			(at 0.635 0)
			(size 0.762 1.6256)
			(layers "F.Cu" "F.Mask" "F.Paste")
			(net "P12V")
		)
		(pad "4" smd rect
			(at 1.905 0)
			(size 0.762 1.6256)
			(layers "F.Cu" "F.Mask" "F.Paste")
			(net "ADM1276_GATE_DRV1")
		)
		(pad "5" smd rect
			(at 0 -3.69951)
			(size 5.0038 5.207)
			(layers "F.Cu" "F.Mask" "F.Paste")
			(net "P12V_SENSE_TRACE")
		)
	)
)
